(kicad_pcb
	(version 20260206)
	(generator "pcbnew")
	(generator_version "10.0")
	(general
		(thickness 1.6)
		(legacy_teardrops no)
	)
	(paper "A4")
	(title_block
		(title "Wiwynn_Tioga_Pass_MB.brd")
		(comment 1 "Tioga Pass / footprints 2388-2394 of 4770")
	)
	(layers
		(0 "F.Cu" signal "TOP")
		(4 "In1.Cu" signal "L2GND")
		(6 "In2.Cu" signal "L3")
		(8 "In3.Cu" signal "L4GND")
		(10 "In4.Cu" signal "L5")
		(12 "In5.Cu" signal "L6GND")
		(14 "In6.Cu" signal "L7VCC")
		(16 "In7.Cu" signal "L8VCC")
		(18 "In8.Cu" signal "L9GND")
		(20 "In9.Cu" signal "L10")
		(22 "In10.Cu" signal "L11GND")
		(24 "In11.Cu" signal "L12")
		(26 "In12.Cu" signal "L13GND")
		(2 "B.Cu" signal "BOTTOM")
		(9 "F.Adhes" user "F.Adhesive")
		(11 "B.Adhes" user "B.Adhesive")
		(13 "F.Paste" user "Package Geometry/Pastemask Top")
		(15 "B.Paste" user "Package Geometry/Pastemask Bottom")
		(5 "F.SilkS" user "Ref Des/Silkscreen Top")
		(7 "B.SilkS" user "Ref Des/Silkscreen Bottom")
		(1 "F.Mask" user "Board Geometry/Soldermask Top")
		(3 "B.Mask" user "Board Geometry/Soldermask Bottom")
		(17 "Dwgs.User" user "User.Drawings")
		(19 "Cmts.User" user "User.Comments")
		(21 "Eco1.User" user "User.Eco1")
		(23 "Eco2.User" user "User.Eco2")
		(25 "Edge.Cuts" user "Board Geometry/Outline")
		(27 "Margin" user)
		(31 "F.CrtYd" user "Package Geometry/Place Bound Top")
		(29 "B.CrtYd" user "Package Geometry/Place Bound Bottom")
		(35 "F.Fab" user "Ref Des/Assembly Top")
		(33 "B.Fab" user "Ref Des/Assembly Bottom")
	)
	(footprint ""
		(layer "B.Cu")
		(at 9.398 -130.9624 90)
		(property "Reference" "R9M4"
			(at -1.59893 2.286 180)
			(unlocked yes)
			(layer "B.SilkS")
			(effects
				(font
					(size 0.7874 0.5842)
					(thickness 0.1524)
				)
				(justify mirror)
			)
		)
		(property "Value" ""
			(at 0 0 90)
			(layer "B.Fab")
			(effects
				(font
					(size 1.27 1.27)
				)
				(justify mirror)
			)
		)
		(duplicate_pad_numbers_are_jumpers no)
		(fp_line
			(start 0.9017 1.951736)
			(end 0.9017 0.823468)
			(stroke
				(width 0.1524)
				(type default)
			)
			(layer "B.SilkS")
		)
		(fp_line
			(start -0.9017 1.952498)
			(end -0.9017 0.853948)
			(stroke
				(width 0.1524)
				(type default)
			)
			(layer "B.SilkS")
		)
		(fp_poly
			(pts
				(xy 0.9017 -0.3048) (xy -0.9017 -0.3048) (xy -0.9017 3.0988) (xy 0.9017 3.0988)
			)
			(stroke
				(width 0)
				(type default)
			)
			(fill no)
			(layer "B.CrtYd")
		)
		(fp_line
			(start 0.9017 -0.3048)
			(end 0.9017 3.0988)
			(stroke
				(width 0.1)
				(type default)
			)
			(layer "B.Fab")
		)
		(fp_line
			(start -0.9017 -0.3048)
			(end 0.9017 -0.3048)
			(stroke
				(width 0.1)
				(type default)
			)
			(layer "B.Fab")
		)
		(fp_line
			(start 0.9017 3.0988)
			(end -0.9017 3.0988)
			(stroke
				(width 0.1)
				(type default)
			)
			(layer "B.Fab")
		)
		(fp_line
			(start -0.9017 3.0988)
			(end -0.9017 -0.3048)
			(stroke
				(width 0.1)
				(type default)
			)
			(layer "B.Fab")
		)
		(pad "1" smd rect
			(at 0 0 270)
			(size 1.524 1.016)
			(layers "B.Cu" "B.Mask" "B.Paste")
			(net "P12V_STBY")
		)
		(pad "2" smd rect
			(at 0 2.794 270)
			(size 1.524 1.016)
			(layers "B.Cu" "B.Mask" "B.Paste")
			(net "P12V_NVDIMM_KLM")
		)
		(zone
			(layer "B.Cu")
			(hatch none 0.5)
			(connect_pads
				(clearance 0)
			)
			(min_thickness 0.25)
			(keepout
				(tracks allowed)
				(vias not_allowed)
				(pads allowed)
				(copperpour not_allowed)
				(footprints allowed)
			)
			(placement
				(enabled no)
				(sheetname "")
			)
			(fill
				(thermal_gap 0.5)
				(thermal_bridge_width 0.5)
				(island_removal_mode 0)
			)
			(polygon
				(pts
					(xy 9.906 -130.2004) (xy 11.684 -130.2004) (xy 11.684 -131.7244) (xy 9.906 -131.7244)
				)
			)
		)
	)
	(footprint ""
		(layer "B.Cu")
		(at 113.702592 -77.810614)
		(property "Reference" "C7P11"
			(at 0 0 0)
			(layer "B.SilkS")
			(hide yes)
			(effects
				(font
					(size 1.27 1.27)
				)
				(justify mirror)
			)
		)
		(property "Value" ""
			(at 0 0 0)
			(layer "B.Fab")
			(effects
				(font
					(size 1.27 1.27)
				)
				(justify mirror)
			)
		)
		(duplicate_pad_numbers_are_jumpers no)
		(fp_poly
			(pts
				(xy 0.7239 -0.2159) (xy -0.7239 -0.2159) (xy -0.7239 1.9939) (xy 0.7239 1.9939)
			)
			(stroke
				(width 0)
				(type default)
			)
			(fill no)
			(layer "B.CrtYd")
		)
		(fp_line
			(start -0.7239 -0.2159)
			(end 0.7239 -0.2159)
			(stroke
				(width 0.1)
				(type default)
			)
			(layer "B.Fab")
		)
		(fp_line
			(start -0.7239 1.9939)
			(end -0.7239 -0.2159)
			(stroke
				(width 0.1)
				(type default)
			)
			(layer "B.Fab")
		)
		(fp_line
			(start 0.7239 -0.2159)
			(end 0.7239 1.9939)
			(stroke
				(width 0.1)
				(type default)
			)
			(layer "B.Fab")
		)
		(fp_line
			(start 0.7239 1.9939)
			(end -0.7239 1.9939)
			(stroke
				(width 0.1)
				(type default)
			)
			(layer "B.Fab")
		)
		(pad "1" smd rect
			(at 0 0 180)
			(size 1.27 1.016)
			(layers "B.Cu" "B.Mask" "B.Paste")
			(net "PVCCMCP_CPU1")
		)
		(pad "2" smd rect
			(at 0 1.778 180)
			(size 1.27 1.016)
			(layers "B.Cu" "B.Mask" "B.Paste")
			(net "GND")
		)
		(zone
			(layer "B.Cu")
			(hatch none 0.5)
			(connect_pads
				(clearance 0)
			)
			(min_thickness 0.25)
			(keepout
				(tracks not_allowed)
				(vias allowed)
				(pads allowed)
				(copperpour not_allowed)
				(footprints allowed)
			)
			(placement
				(enabled no)
				(sheetname "")
			)
			(fill
				(thermal_gap 0.5)
				(thermal_bridge_width 0.5)
				(island_removal_mode 0)
			)
			(polygon
				(pts
					(xy 114.337592 -77.302614) (xy 113.067592 -77.302614) (xy 113.067592 -76.540614) (xy 114.337592 -76.540614)
				)
			)
		)
	)
	(footprint ""
		(layer "B.Cu")
		(at 20.153884 -134.189978 -90)
		(property "Reference" "R9M21"
			(at 0 0 90)
			(layer "B.SilkS")
			(hide yes)
			(effects
				(font
					(size 1.27 1.27)
				)
				(justify mirror)
			)
		)
		(property "Value" ""
			(at 0 0 90)
			(layer "B.Fab")
			(effects
				(font
					(size 1.27 1.27)
				)
				(justify mirror)
			)
		)
		(duplicate_pad_numbers_are_jumpers no)
		(fp_poly
			(pts
				(xy 0.2794 -0.1016) (xy -0.2794 -0.1016) (xy -0.2794 0.9906) (xy 0.2794 0.9906)
			)
			(stroke
				(width 0)
				(type default)
			)
			(fill no)
			(layer "B.CrtYd")
		)
		(fp_line
			(start -0.2794 0.9906)
			(end -0.2794 -0.1016)
			(stroke
				(width 0.1)
				(type default)
			)
			(layer "B.Fab")
		)
		(fp_line
			(start 0.2794 0.9906)
			(end -0.2794 0.9906)
			(stroke
				(width 0.1)
				(type default)
			)
			(layer "B.Fab")
		)
		(fp_line
			(start -0.2794 -0.1016)
			(end 0.2794 -0.1016)
			(stroke
				(width 0.1)
				(type default)
			)
			(layer "B.Fab")
		)
		(fp_line
			(start 0.2794 -0.1016)
			(end 0.2794 0.9906)
			(stroke
				(width 0.1)
				(type default)
			)
			(layer "B.Fab")
		)
		(pad "1" smd rect
			(at 0 0 90)
			(size 0.508 0.508)
			(layers "B.Cu" "B.Mask" "B.Paste")
			(net "SMB_LAN_STBY_LVC3_SDA")
		)
		(pad "2" smd rect
			(at 0 0.889 90)
			(size 0.508 0.508)
			(layers "B.Cu" "B.Mask" "B.Paste")
			(net "SMB_PIROM_CPU1_SDA")
		)
		(zone
			(layer "B.Cu")
			(hatch none 0.5)
			(connect_pads
				(clearance 0)
			)
			(min_thickness 0.25)
			(keepout
				(tracks not_allowed)
				(vias allowed)
				(pads allowed)
				(copperpour not_allowed)
				(footprints allowed)
			)
			(placement
				(enabled no)
				(sheetname "")
			)
			(fill
				(thermal_gap 0.5)
				(thermal_bridge_width 0.5)
				(island_removal_mode 0)
			)
			(polygon
				(pts
					(xy 19.518884 -133.935978) (xy 19.518884 -134.443978) (xy 19.899884 -134.443978) (xy 19.899884 -133.935978)
				)
			)
		)
		(zone
			(layer "B.Cu")
			(hatch none 0.5)
			(connect_pads
				(clearance 0)
			)
			(min_thickness 0.25)
			(keepout
				(tracks allowed)
				(vias not_allowed)
				(pads allowed)
				(copperpour not_allowed)
				(footprints allowed)
			)
			(placement
				(enabled no)
				(sheetname "")
			)
			(fill
				(thermal_gap 0.5)
				(thermal_bridge_width 0.5)
				(island_removal_mode 0)
			)
			(polygon
				(pts
					(xy 19.899884 -133.935978) (xy 19.899884 -134.443978) (xy 19.518884 -134.443978) (xy 19.518884 -133.935978)
				)
			)
		)
	)
	(footprint ""
		(layer "B.Cu")
		(at 29.436568 -145.3642)
		(property "Reference" "R9L6"
			(at 0 0 0)
			(layer "B.SilkS")
			(hide yes)
			(effects
				(font
					(size 1.27 1.27)
				)
				(justify mirror)
			)
		)
		(property "Value" ""
			(at 0 0 0)
			(layer "B.Fab")
			(effects
				(font
					(size 1.27 1.27)
				)
				(justify mirror)
			)
		)
		(duplicate_pad_numbers_are_jumpers no)
		(fp_poly
			(pts
				(xy 0.2794 -0.1016) (xy -0.2794 -0.1016) (xy -0.2794 0.9906) (xy 0.2794 0.9906)
			)
			(stroke
				(width 0)
				(type default)
			)
			(fill no)
			(layer "B.CrtYd")
		)
		(fp_line
			(start -0.2794 -0.1016)
			(end 0.2794 -0.1016)
			(stroke
				(width 0.1)
				(type default)
			)
			(layer "B.Fab")
		)
		(fp_line
			(start -0.2794 0.9906)
			(end -0.2794 -0.1016)
			(stroke
				(width 0.1)
				(type default)
			)
			(layer "B.Fab")
		)
		(fp_line
			(start 0.2794 -0.1016)
			(end 0.2794 0.9906)
			(stroke
				(width 0.1)
				(type default)
			)
			(layer "B.Fab")
		)
		(fp_line
			(start 0.2794 0.9906)
			(end -0.2794 0.9906)
			(stroke
				(width 0.1)
				(type default)
			)
			(layer "B.Fab")
		)
		(pad "1" smd rect
			(at 0 0 180)
			(size 0.508 0.508)
			(layers "B.Cu" "B.Mask" "B.Paste")
			(net "M_L_VREF")
		)
		(pad "2" smd rect
			(at 0 0.889 180)
			(size 0.508 0.508)
			(layers "B.Cu" "B.Mask" "B.Paste")
			(net "GND")
		)
		(zone
			(layer "B.Cu")
			(hatch none 0.5)
			(connect_pads
				(clearance 0)
			)
			(min_thickness 0.25)
			(keepout
				(tracks allowed)
				(vias not_allowed)
				(pads allowed)
				(copperpour not_allowed)
				(footprints allowed)
			)
			(placement
				(enabled no)
				(sheetname "")
			)
			(fill
				(thermal_gap 0.5)
				(thermal_bridge_width 0.5)
				(island_removal_mode 0)
			)
			(polygon
				(pts
					(xy 29.690568 -145.1102) (xy 29.182568 -145.1102) (xy 29.182568 -144.7292) (xy 29.690568 -144.7292)
				)
			)
		)
		(zone
			(layer "B.Cu")
			(hatch none 0.5)
			(connect_pads
				(clearance 0)
			)
			(min_thickness 0.25)
			(keepout
				(tracks not_allowed)
				(vias allowed)
				(pads allowed)
				(copperpour not_allowed)
				(footprints allowed)
			)
			(placement
				(enabled no)
				(sheetname "")
			)
			(fill
				(thermal_gap 0.5)
				(thermal_bridge_width 0.5)
				(island_removal_mode 0)
			)
			(polygon
				(pts
					(xy 29.690568 -144.7292) (xy 29.182568 -144.7292) (xy 29.182568 -145.1102) (xy 29.690568 -145.1102)
				)
			)
		)
	)
	(footprint ""
		(layer "B.Cu")
		(at 482.5238 -151.0284)
		(property "Reference" "R1L9"
			(at 0 0 0)
			(layer "B.SilkS")
			(hide yes)
			(effects
				(font
					(size 1.27 1.27)
				)
				(justify mirror)
			)
		)
		(property "Value" ""
			(at 0 0 0)
			(layer "B.Fab")
			(effects
				(font
					(size 1.27 1.27)
				)
				(justify mirror)
			)
		)
		(duplicate_pad_numbers_are_jumpers no)
		(fp_poly
			(pts
				(xy 0.2794 -0.1016) (xy -0.2794 -0.1016) (xy -0.2794 0.9906) (xy 0.2794 0.9906)
			)
			(stroke
				(width 0)
				(type default)
			)
			(fill no)
			(layer "B.CrtYd")
		)
		(fp_line
			(start -0.2794 -0.1016)
			(end 0.2794 -0.1016)
			(stroke
				(width 0.1)
				(type default)
			)
			(layer "B.Fab")
		)
		(fp_line
			(start -0.2794 0.9906)
			(end -0.2794 -0.1016)
			(stroke
				(width 0.1)
				(type default)
			)
			(layer "B.Fab")
		)
		(fp_line
			(start 0.2794 -0.1016)
			(end 0.2794 0.9906)
			(stroke
				(width 0.1)
				(type default)
			)
			(layer "B.Fab")
		)
		(fp_line
			(start 0.2794 0.9906)
			(end -0.2794 0.9906)
			(stroke
				(width 0.1)
				(type default)
			)
			(layer "B.Fab")
		)
		(pad "1" smd rect
			(at 0 0 180)
			(size 0.508 0.508)
			(layers "B.Cu" "B.Mask" "B.Paste")
			(net "P12V_STBY")
		)
		(pad "2" smd rect
			(at 0 0.889 180)
			(size 0.508 0.508)
			(layers "B.Cu" "B.Mask" "B.Paste")
			(net "FM_CPLD_DBG_PWR_EN")
		)
		(zone
			(layer "B.Cu")
			(hatch none 0.5)
			(connect_pads
				(clearance 0)
			)
			(min_thickness 0.25)
			(keepout
				(tracks allowed)
				(vias not_allowed)
				(pads allowed)
				(copperpour not_allowed)
				(footprints allowed)
			)
			(placement
				(enabled no)
				(sheetname "")
			)
			(fill
				(thermal_gap 0.5)
				(thermal_bridge_width 0.5)
				(island_removal_mode 0)
			)
			(polygon
				(pts
					(xy 482.7778 -150.7744) (xy 482.2698 -150.7744) (xy 482.2698 -150.3934) (xy 482.7778 -150.3934)
				)
			)
		)
		(zone
			(layer "B.Cu")
			(hatch none 0.5)
			(connect_pads
				(clearance 0)
			)
			(min_thickness 0.25)
			(keepout
				(tracks not_allowed)
				(vias allowed)
				(pads allowed)
				(copperpour not_allowed)
				(footprints allowed)
			)
			(placement
				(enabled no)
				(sheetname "")
			)
			(fill
				(thermal_gap 0.5)
				(thermal_bridge_width 0.5)
				(island_removal_mode 0)
			)
			(polygon
				(pts
					(xy 482.7778 -150.3934) (xy 482.2698 -150.3934) (xy 482.2698 -150.7744) (xy 482.7778 -150.7744)
				)
			)
		)
	)
	(footprint ""
		(layer "B.Cu")
		(at 440.67222 -58.02376 90)
		(property "Reference" "R1W40"
			(at 0.8382 -0.67818 90)
			(unlocked yes)
			(layer "B.SilkS")
			(effects
				(font
					(size 0.4064 0.254)
					(thickness 0.1524)
				)
				(justify left mirror)
			)
		)
		(property "Value" ""
			(at 0 0 90)
			(layer "B.Fab")
			(effects
				(font
					(size 1.27 1.27)
				)
				(justify mirror)
			)
		)
		(duplicate_pad_numbers_are_jumpers no)
		(fp_poly
			(pts
				(xy 0.2794 -0.1016) (xy -0.2794 -0.1016) (xy -0.2794 0.9906) (xy 0.2794 0.9906)
			)
			(stroke
				(width 0)
				(type default)
			)
			(fill no)
			(layer "B.CrtYd")
		)
		(fp_line
			(start 0.2794 -0.1016)
			(end 0.2794 0.9906)
			(stroke
				(width 0.1)
				(type default)
			)
			(layer "B.Fab")
		)
		(fp_line
			(start -0.2794 -0.1016)
			(end 0.2794 -0.1016)
			(stroke
				(width 0.1)
				(type default)
			)
			(layer "B.Fab")
		)
		(fp_line
			(start 0.2794 0.9906)
			(end -0.2794 0.9906)
			(stroke
				(width 0.1)
				(type default)
			)
			(layer "B.Fab")
		)
		(fp_line
			(start -0.2794 0.9906)
			(end -0.2794 -0.1016)
			(stroke
				(width 0.1)
				(type default)
			)
			(layer "B.Fab")
		)
		(pad "1" smd rect
			(at 0 0 270)
			(size 0.508 0.508)
			(layers "B.Cu" "B.Mask" "B.Paste")
			(net "P3V3_STBY")
		)
		(pad "2" smd rect
			(at 0 0.889 270)
			(size 0.508 0.508)
			(layers "B.Cu" "B.Mask" "B.Paste")
			(net "EXT_MDIO_I2C_SEL")
		)
		(zone
			(layer "B.Cu")
			(hatch none 0.5)
			(connect_pads
				(clearance 0)
			)
			(min_thickness 0.25)
			(keepout
				(tracks allowed)
				(vias not_allowed)
				(pads allowed)
				(copperpour not_allowed)
				(footprints allowed)
			)
			(placement
				(enabled no)
				(sheetname "")
			)
			(fill
				(thermal_gap 0.5)
				(thermal_bridge_width 0.5)
				(island_removal_mode 0)
			)
			(polygon
				(pts
					(xy 440.92622 -58.27776) (xy 440.92622 -57.76976) (xy 441.30722 -57.76976) (xy 441.30722 -58.27776)
				)
			)
		)
		(zone
			(layer "B.Cu")
			(hatch none 0.5)
			(connect_pads
				(clearance 0)
			)
			(min_thickness 0.25)
			(keepout
				(tracks not_allowed)
				(vias allowed)
				(pads allowed)
				(copperpour not_allowed)
				(footprints allowed)
			)
			(placement
				(enabled no)
				(sheetname "")
			)
			(fill
				(thermal_gap 0.5)
				(thermal_bridge_width 0.5)
				(island_removal_mode 0)
			)
			(polygon
				(pts
					(xy 441.30722 -58.27776) (xy 441.30722 -57.76976) (xy 440.92622 -57.76976) (xy 440.92622 -58.27776)
				)
			)
		)
	)
	(footprint ""
		(layer "B.Cu")
		(at 470.662 -116.84 180)
		(property "Reference" "R1M16"
			(at 0 0 0)
			(layer "B.SilkS")
			(hide yes)
			(effects
				(font
					(size 1.27 1.27)
				)
				(justify mirror)
			)
		)
		(property "Value" ""
			(at 0 0 0)
			(layer "B.Fab")
			(effects
				(font
					(size 1.27 1.27)
				)
				(justify mirror)
			)
		)
		(duplicate_pad_numbers_are_jumpers no)
		(fp_poly
			(pts
				(xy 0.2794 -0.1016) (xy -0.2794 -0.1016) (xy -0.2794 0.9906) (xy 0.2794 0.9906)
			)
			(stroke
				(width 0)
				(type default)
			)
			(fill no)
			(layer "B.CrtYd")
		)
		(fp_line
			(start 0.2794 0.9906)
			(end -0.2794 0.9906)
			(stroke
				(width 0.1)
				(type default)
			)
			(layer "B.Fab")
		)
		(fp_line
			(start 0.2794 -0.1016)
			(end 0.2794 0.9906)
			(stroke
				(width 0.1)
				(type default)
			)
			(layer "B.Fab")
		)
		(fp_line
			(start -0.2794 0.9906)
			(end -0.2794 -0.1016)
			(stroke
				(width 0.1)
				(type default)
			)
			(layer "B.Fab")
		)
		(fp_line
			(start -0.2794 -0.1016)
			(end 0.2794 -0.1016)
			(stroke
				(width 0.1)
				(type default)
			)
			(layer "B.Fab")
		)
		(pad "1" smd rect
			(at 0 0)
			(size 0.508 0.508)
			(layers "B.Cu" "B.Mask" "B.Paste")
			(net "RMII_BMC_OCP_RXD1")
		)
		(pad "2" smd rect
			(at 0 0.889)
			(size 0.508 0.508)
			(layers "B.Cu" "B.Mask" "B.Paste")
			(net "RMII_BMC_OCP_RXD1_R")
		)
		(zone
			(layer "B.Cu")
			(hatch none 0.5)
			(connect_pads
				(clearance 0)
			)
			(min_thickness 0.25)
			(keepout
				(tracks not_allowed)
				(vias allowed)
				(pads allowed)
				(copperpour not_allowed)
				(footprints allowed)
			)
			(placement
				(enabled no)
				(sheetname "")
			)
			(fill
				(thermal_gap 0.5)
				(thermal_bridge_width 0.5)
				(island_removal_mode 0)
			)
			(polygon
				(pts
					(xy 470.408 -117.475) (xy 470.916 -117.475) (xy 470.916 -117.094) (xy 470.408 -117.094)
				)
			)
		)
		(zone
			(layer "B.Cu")
			(hatch none 0.5)
			(connect_pads
				(clearance 0)
			)
			(min_thickness 0.25)
			(keepout
				(tracks allowed)
				(vias not_allowed)
				(pads allowed)
				(copperpour not_allowed)
				(footprints allowed)
			)
			(placement
				(enabled no)
				(sheetname "")
			)
			(fill
				(thermal_gap 0.5)
				(thermal_bridge_width 0.5)
				(island_removal_mode 0)
			)
			(polygon
				(pts
					(xy 470.408 -117.094) (xy 470.916 -117.094) (xy 470.916 -117.475) (xy 470.408 -117.475)
				)
			)
		)
	)
)
